(kicad_pcb
	(version 20260206)
	(generator "pcbnew")
	(generator_version "10.0")
	(general
		(thickness 1.6)
		(legacy_teardrops no)
	)
	(paper "A4")
	(title_block
		(title "03242023_DA0F0TMBIJ0_F0T_Motherboard_J_brd_V01_OCP.brd")
		(comment 1 "Grand Teton / footprints 3354-3360 of 6105")
	)
	(layers
		(0 "F.Cu" signal "TOP")
		(4 "In1.Cu" signal "GND")
		(6 "In2.Cu" signal "IN1")
		(8 "In3.Cu" signal "GND1")
		(10 "In4.Cu" signal "IN2")
		(12 "In5.Cu" signal "GND2")
		(14 "In6.Cu" signal "IN3")
		(16 "In7.Cu" signal "GND3")
		(18 "In8.Cu" signal "VCC")
		(20 "In9.Cu" signal "VCC1")
		(22 "In10.Cu" signal "GND4")
		(24 "In11.Cu" signal "IN4")
		(26 "In12.Cu" signal "GND5")
		(28 "In13.Cu" signal "IN5")
		(30 "In14.Cu" signal "GND6")
		(32 "In15.Cu" signal "IN6")
		(34 "In16.Cu" signal "GND7")
		(2 "B.Cu" signal "BOTTOM")
		(9 "F.Adhes" user "F.Adhesive")
		(11 "B.Adhes" user "B.Adhesive")
		(13 "F.Paste" user "Package Geometry/Pastemask Top")
		(15 "B.Paste" user "Package Geometry/Pastemask Bottom")
		(5 "F.SilkS" user "Ref Des/Silkscreen Top")
		(7 "B.SilkS" user "Ref Des/Silkscreen Bottom")
		(1 "F.Mask" user "Board Geometry/Soldermask Top")
		(3 "B.Mask" user "Board Geometry/Soldermask Bottom")
		(17 "Dwgs.User" user "User.Drawings")
		(19 "Cmts.User" user "User.Comments")
		(21 "Eco1.User" user "User.Eco1")
		(23 "Eco2.User" user "User.Eco2")
		(25 "Edge.Cuts" user "Board Geometry/Outline")
		(27 "Margin" user)
		(31 "F.CrtYd" user "Package Geometry/Place Bound Top")
		(29 "B.CrtYd" user "Package Geometry/Place Bound Bottom")
		(35 "F.Fab" user "Ref Des/Assembly Top")
		(33 "B.Fab" user "Ref Des/Assembly Bottom")
	)
	(footprint ""
		(layer "F.Cu")
		(at 159.267144 -52.851304 180)
		(property "Reference" "R3575"
			(at 0 0 180)
			(layer "F.SilkS")
			(hide yes)
			(effects
				(font
					(size 1.27 1.27)
				)
			)
		)
		(property "Value" ""
			(at 0 0 180)
			(layer "F.Fab")
			(effects
				(font
					(size 1.27 1.27)
				)
			)
		)
		(duplicate_pad_numbers_are_jumpers no)
		(fp_line
			(start 0.7874 0.4064)
			(end -0.7874 0.4064)
			(stroke
				(width 0.1524)
				(type default)
			)
			(layer "F.SilkS")
		)
		(fp_line
			(start 0.7874 -0.4064)
			(end 0.7874 0.4064)
			(stroke
				(width 0.1524)
				(type default)
			)
			(layer "F.SilkS")
		)
		(fp_line
			(start -0.7874 0.4064)
			(end -0.7874 -0.4064)
			(stroke
				(width 0.1524)
				(type default)
			)
			(layer "F.SilkS")
		)
		(fp_line
			(start -0.7874 -0.4064)
			(end 0.7874 -0.4064)
			(stroke
				(width 0.1524)
				(type default)
			)
			(layer "F.SilkS")
		)
		(fp_line
			(start 0.67945 0.3048)
			(end 0.120396 0.3048)
			(stroke
				(width 0.1)
				(type default)
			)
			(layer "F.Fab")
		)
		(fp_line
			(start 0.67945 -0.3048)
			(end 0.67945 0.3048)
			(stroke
				(width 0.1)
				(type default)
			)
			(layer "F.Fab")
		)
		(fp_line
			(start 0.12065 -0.2794)
			(end 0.12065 -0.3048)
			(stroke
				(width 0.1)
				(type default)
			)
			(layer "F.Fab")
		)
		(fp_line
			(start 0.12065 -0.3048)
			(end 0.67945 -0.3048)
			(stroke
				(width 0.1)
				(type default)
			)
			(layer "F.Fab")
		)
		(fp_line
			(start 0.120396 0.3048)
			(end 0.120396 0.2794)
			(stroke
				(width 0.1)
				(type default)
			)
			(layer "F.Fab")
		)
		(fp_line
			(start 0.120396 0.2794)
			(end -0.12065 0.2794)
			(stroke
				(width 0.1)
				(type default)
			)
			(layer "F.Fab")
		)
		(fp_line
			(start -0.12065 0.3048)
			(end -0.67945 0.3048)
			(stroke
				(width 0.1)
				(type default)
			)
			(layer "F.Fab")
		)
		(fp_line
			(start -0.12065 0.2794)
			(end -0.12065 0.3048)
			(stroke
				(width 0.1)
				(type default)
			)
			(layer "F.Fab")
		)
		(fp_line
			(start -0.12065 -0.2794)
			(end 0.12065 -0.2794)
			(stroke
				(width 0.1)
				(type default)
			)
			(layer "F.Fab")
		)
		(fp_line
			(start -0.12065 -0.305054)
			(end -0.12065 -0.2794)
			(stroke
				(width 0.1)
				(type default)
			)
			(layer "F.Fab")
		)
		(fp_line
			(start -0.67945 0.3048)
			(end -0.67945 -0.305054)
			(stroke
				(width 0.1)
				(type default)
			)
			(layer "F.Fab")
		)
		(fp_line
			(start -0.67945 -0.305054)
			(end -0.12065 -0.305054)
			(stroke
				(width 0.1)
				(type default)
			)
			(layer "F.Fab")
		)
		(pad "1" smd circle
			(at -0.40005 0 180)
			(size 0 0)
			(layers "F.Cu" "F.Mask" "F.Paste")
			(net "P3V3_M2_0")
		)
		(pad "2" smd circle
			(at 0.40005 0 180)
			(size 0 0)
			(layers "F.Cu" "F.Mask" "F.Paste")
			(net "VSENSE_P12V_INA230_4_INN")
		)
	)
	(footprint ""
		(layer "F.Cu")
		(at 303.523904 -32.462216)
		(property "Reference" "C611"
			(at 0 0 0)
			(layer "F.SilkS")
			(hide yes)
			(effects
				(font
					(size 1.27 1.27)
				)
			)
		)
		(property "Value" ""
			(at 0 0 0)
			(layer "F.Fab")
			(effects
				(font
					(size 1.27 1.27)
				)
			)
		)
		(duplicate_pad_numbers_are_jumpers no)
		(fp_line
			(start -0.7874 -0.4064)
			(end 0.7874 -0.4064)
			(stroke
				(width 0.1524)
				(type default)
			)
			(layer "F.SilkS")
		)
		(fp_line
			(start -0.7874 0.4064)
			(end -0.7874 -0.4064)
			(stroke
				(width 0.1524)
				(type default)
			)
			(layer "F.SilkS")
		)
		(fp_line
			(start 0.7874 -0.4064)
			(end 0.7874 0.4064)
			(stroke
				(width 0.1524)
				(type default)
			)
			(layer "F.SilkS")
		)
		(fp_line
			(start 0.7874 0.4064)
			(end -0.7874 0.4064)
			(stroke
				(width 0.1524)
				(type default)
			)
			(layer "F.SilkS")
		)
		(fp_line
			(start -0.67945 -0.305054)
			(end -0.12065 -0.305054)
			(stroke
				(width 0.1)
				(type default)
			)
			(layer "F.Fab")
		)
		(fp_line
			(start -0.67945 0.3048)
			(end -0.67945 -0.305054)
			(stroke
				(width 0.1)
				(type default)
			)
			(layer "F.Fab")
		)
		(fp_line
			(start -0.12065 -0.305054)
			(end -0.12065 -0.2794)
			(stroke
				(width 0.1)
				(type default)
			)
			(layer "F.Fab")
		)
		(fp_line
			(start -0.12065 -0.2794)
			(end 0.12065 -0.2794)
			(stroke
				(width 0.1)
				(type default)
			)
			(layer "F.Fab")
		)
		(fp_line
			(start -0.12065 0.2794)
			(end -0.12065 0.3048)
			(stroke
				(width 0.1)
				(type default)
			)
			(layer "F.Fab")
		)
		(fp_line
			(start -0.12065 0.3048)
			(end -0.67945 0.3048)
			(stroke
				(width 0.1)
				(type default)
			)
			(layer "F.Fab")
		)
		(fp_line
			(start 0.120396 0.2794)
			(end -0.12065 0.2794)
			(stroke
				(width 0.1)
				(type default)
			)
			(layer "F.Fab")
		)
		(fp_line
			(start 0.120396 0.3048)
			(end 0.120396 0.2794)
			(stroke
				(width 0.1)
				(type default)
			)
			(layer "F.Fab")
		)
		(fp_line
			(start 0.12065 -0.3048)
			(end 0.67945 -0.3048)
			(stroke
				(width 0.1)
				(type default)
			)
			(layer "F.Fab")
		)
		(fp_line
			(start 0.12065 -0.2794)
			(end 0.12065 -0.3048)
			(stroke
				(width 0.1)
				(type default)
			)
			(layer "F.Fab")
		)
		(fp_line
			(start 0.67945 -0.3048)
			(end 0.67945 0.3048)
			(stroke
				(width 0.1)
				(type default)
			)
			(layer "F.Fab")
		)
		(fp_line
			(start 0.67945 0.3048)
			(end 0.120396 0.3048)
			(stroke
				(width 0.1)
				(type default)
			)
			(layer "F.Fab")
		)
		(pad "1" smd circle
			(at -0.40005 0)
			(size 0 0)
			(layers "F.Cu" "F.Mask" "F.Paste")
			(net "P3V3_RTC_AUX")
		)
		(pad "2" smd circle
			(at 0.40005 0)
			(size 0 0)
			(layers "F.Cu" "F.Mask" "F.Paste")
			(net "GND")
		)
	)
	(footprint ""
		(layer "F.Cu")
		(at 429.272192 -164.780722 180)
		(property "Reference" "PL6"
			(at -2.44094 3.725164 0)
			(unlocked yes)
			(layer "F.SilkS")
			(effects
				(font
					(size 0.7874 0.5842)
					(thickness 0.1524)
				)
				(justify left)
			)
		)
		(property "Value" ""
			(at 0 0 180)
			(layer "F.Fab")
			(effects
				(font
					(size 1.27 1.27)
				)
			)
		)
		(duplicate_pad_numbers_are_jumpers no)
		(fp_line
			(start 2.249932 2.249932)
			(end -2.249932 2.249932)
			(stroke
				(width 0.1524)
				(type default)
			)
			(layer "F.SilkS")
		)
		(fp_line
			(start 2.249932 1.3843)
			(end 2.249932 2.249932)
			(stroke
				(width 0.1524)
				(type default)
			)
			(layer "F.SilkS")
		)
		(fp_line
			(start 2.249932 -2.249932)
			(end 2.249932 -1.3843)
			(stroke
				(width 0.1524)
				(type default)
			)
			(layer "F.SilkS")
		)
		(fp_line
			(start -2.249932 2.249932)
			(end -2.249932 1.3843)
			(stroke
				(width 0.1524)
				(type default)
			)
			(layer "F.SilkS")
		)
		(fp_line
			(start -2.249932 -1.3843)
			(end -2.249932 -2.249932)
			(stroke
				(width 0.1524)
				(type default)
			)
			(layer "F.SilkS")
		)
		(fp_line
			(start -2.249932 -2.249932)
			(end 2.249932 -2.249932)
			(stroke
				(width 0.1524)
				(type default)
			)
			(layer "F.SilkS")
		)
		(fp_line
			(start 2.249932 2.249932)
			(end -2.249932 2.249932)
			(stroke
				(width 0.1)
				(type default)
			)
			(layer "F.Fab")
		)
		(fp_line
			(start 2.249932 -2.249932)
			(end 2.249932 2.249932)
			(stroke
				(width 0.1)
				(type default)
			)
			(layer "F.Fab")
		)
		(fp_line
			(start -2.249932 2.249932)
			(end -2.249932 -2.249932)
			(stroke
				(width 0.1)
				(type default)
			)
			(layer "F.Fab")
		)
		(fp_line
			(start -2.249932 -2.249932)
			(end 2.249932 -2.249932)
			(stroke
				(width 0.1)
				(type default)
			)
			(layer "F.Fab")
		)
		(pad "1" smd rect
			(at -1.82499 0 180)
			(size 1.0668 2.5146)
			(layers "F.Cu" "F.Mask" "F.Paste")
			(net "P12V_AUX")
		)
		(pad "2" smd rect
			(at 1.82499 0 180)
			(size 1.0668 2.5146)
			(layers "F.Cu" "F.Mask" "F.Paste")
			(net "SW_P12V_PVCCINFAON_CPU0_FLT")
		)
	)
	(footprint ""
		(layer "F.Cu")
		(at 179.352448 -399.207482 180)
		(property "Reference" "PR1133"
			(at 0 0 180)
			(layer "F.SilkS")
			(hide yes)
			(effects
				(font
					(size 1.27 1.27)
				)
			)
		)
		(property "Value" ""
			(at 0 0 180)
			(layer "F.Fab")
			(effects
				(font
					(size 1.27 1.27)
				)
			)
		)
		(duplicate_pad_numbers_are_jumpers no)
		(fp_line
			(start 0.7874 0.4064)
			(end -0.7874 0.4064)
			(stroke
				(width 0.1524)
				(type default)
			)
			(layer "F.SilkS")
		)
		(fp_line
			(start 0.7874 -0.4064)
			(end 0.7874 0.4064)
			(stroke
				(width 0.1524)
				(type default)
			)
			(layer "F.SilkS")
		)
		(fp_line
			(start -0.7874 0.4064)
			(end -0.7874 -0.4064)
			(stroke
				(width 0.1524)
				(type default)
			)
			(layer "F.SilkS")
		)
		(fp_line
			(start -0.7874 -0.4064)
			(end 0.7874 -0.4064)
			(stroke
				(width 0.1524)
				(type default)
			)
			(layer "F.SilkS")
		)
		(fp_line
			(start 0.67945 0.3048)
			(end 0.120396 0.3048)
			(stroke
				(width 0.1)
				(type default)
			)
			(layer "F.Fab")
		)
		(fp_line
			(start 0.67945 -0.3048)
			(end 0.67945 0.3048)
			(stroke
				(width 0.1)
				(type default)
			)
			(layer "F.Fab")
		)
		(fp_line
			(start 0.12065 -0.2794)
			(end 0.12065 -0.3048)
			(stroke
				(width 0.1)
				(type default)
			)
			(layer "F.Fab")
		)
		(fp_line
			(start 0.12065 -0.3048)
			(end 0.67945 -0.3048)
			(stroke
				(width 0.1)
				(type default)
			)
			(layer "F.Fab")
		)
		(fp_line
			(start 0.120396 0.3048)
			(end 0.120396 0.2794)
			(stroke
				(width 0.1)
				(type default)
			)
			(layer "F.Fab")
		)
		(fp_line
			(start 0.120396 0.2794)
			(end -0.12065 0.2794)
			(stroke
				(width 0.1)
				(type default)
			)
			(layer "F.Fab")
		)
		(fp_line
			(start -0.12065 0.3048)
			(end -0.67945 0.3048)
			(stroke
				(width 0.1)
				(type default)
			)
			(layer "F.Fab")
		)
		(fp_line
			(start -0.12065 0.2794)
			(end -0.12065 0.3048)
			(stroke
				(width 0.1)
				(type default)
			)
			(layer "F.Fab")
		)
		(fp_line
			(start -0.12065 -0.2794)
			(end 0.12065 -0.2794)
			(stroke
				(width 0.1)
				(type default)
			)
			(layer "F.Fab")
		)
		(fp_line
			(start -0.12065 -0.305054)
			(end -0.12065 -0.2794)
			(stroke
				(width 0.1)
				(type default)
			)
			(layer "F.Fab")
		)
		(fp_line
			(start -0.67945 0.3048)
			(end -0.67945 -0.305054)
			(stroke
				(width 0.1)
				(type default)
			)
			(layer "F.Fab")
		)
		(fp_line
			(start -0.67945 -0.305054)
			(end -0.12065 -0.305054)
			(stroke
				(width 0.1)
				(type default)
			)
			(layer "F.Fab")
		)
		(pad "1" smd circle
			(at -0.40005 0 180)
			(size 0 0)
			(layers "F.Cu" "F.Mask" "F.Paste")
			(net "HSC_IMON")
		)
		(pad "2" smd circle
			(at 0.40005 0 180)
			(size 0 0)
			(layers "F.Cu" "F.Mask" "F.Paste")
			(net "AGND_HSC")
		)
	)
	(footprint ""
		(layer "F.Cu")
		(at 424.69816 -143.675608 90)
		(property "Reference" "PR4223"
			(at 0 0 90)
			(layer "F.SilkS")
			(hide yes)
			(effects
				(font
					(size 1.27 1.27)
				)
			)
		)
		(property "Value" ""
			(at 0 0 90)
			(layer "F.Fab")
			(effects
				(font
					(size 1.27 1.27)
				)
			)
		)
		(duplicate_pad_numbers_are_jumpers no)
		(fp_line
			(start 0.7874 -0.4064)
			(end 0.7874 0.4064)
			(stroke
				(width 0.1524)
				(type default)
			)
			(layer "F.SilkS")
		)
		(fp_line
			(start -0.7874 -0.4064)
			(end 0.7874 -0.4064)
			(stroke
				(width 0.1524)
				(type default)
			)
			(layer "F.SilkS")
		)
		(fp_line
			(start 0.7874 0.4064)
			(end -0.7874 0.4064)
			(stroke
				(width 0.1524)
				(type default)
			)
			(layer "F.SilkS")
		)
		(fp_line
			(start -0.7874 0.4064)
			(end -0.7874 -0.4064)
			(stroke
				(width 0.1524)
				(type default)
			)
			(layer "F.SilkS")
		)
		(fp_line
			(start -0.12065 -0.305054)
			(end -0.12065 -0.2794)
			(stroke
				(width 0.1)
				(type default)
			)
			(layer "F.Fab")
		)
		(fp_line
			(start -0.67945 -0.305054)
			(end -0.12065 -0.305054)
			(stroke
				(width 0.1)
				(type default)
			)
			(layer "F.Fab")
		)
		(fp_line
			(start 0.67945 -0.3048)
			(end 0.67945 0.3048)
			(stroke
				(width 0.1)
				(type default)
			)
			(layer "F.Fab")
		)
		(fp_line
			(start 0.12065 -0.3048)
			(end 0.67945 -0.3048)
			(stroke
				(width 0.1)
				(type default)
			)
			(layer "F.Fab")
		)
		(fp_line
			(start 0.12065 -0.2794)
			(end 0.12065 -0.3048)
			(stroke
				(width 0.1)
				(type default)
			)
			(layer "F.Fab")
		)
		(fp_line
			(start -0.12065 -0.2794)
			(end 0.12065 -0.2794)
			(stroke
				(width 0.1)
				(type default)
			)
			(layer "F.Fab")
		)
		(fp_line
			(start 0.120396 0.2794)
			(end -0.12065 0.2794)
			(stroke
				(width 0.1)
				(type default)
			)
			(layer "F.Fab")
		)
		(fp_line
			(start -0.12065 0.2794)
			(end -0.12065 0.3048)
			(stroke
				(width 0.1)
				(type default)
			)
			(layer "F.Fab")
		)
		(fp_line
			(start 0.67945 0.3048)
			(end 0.120396 0.3048)
			(stroke
				(width 0.1)
				(type default)
			)
			(layer "F.Fab")
		)
		(fp_line
			(start 0.120396 0.3048)
			(end 0.120396 0.2794)
			(stroke
				(width 0.1)
				(type default)
			)
			(layer "F.Fab")
		)
		(fp_line
			(start -0.12065 0.3048)
			(end -0.67945 0.3048)
			(stroke
				(width 0.1)
				(type default)
			)
			(layer "F.Fab")
		)
		(fp_line
			(start -0.67945 0.3048)
			(end -0.67945 -0.305054)
			(stroke
				(width 0.1)
				(type default)
			)
			(layer "F.Fab")
		)
		(pad "1" smd circle
			(at -0.40005 0 90)
			(size 0 0)
			(layers "F.Cu" "F.Mask" "F.Paste")
			(net "NC_PVCCINFAON_CPU0_ACSP5")
		)
		(pad "2" smd circle
			(at 0.40005 0 90)
			(size 0 0)
			(layers "F.Cu" "F.Mask" "F.Paste")
			(net "GND")
		)
	)
	(footprint ""
		(layer "F.Cu")
		(at 118.09222 -294.01008 180)
		(property "Reference" "C270"
			(at 0 0 180)
			(layer "F.SilkS")
			(hide yes)
			(effects
				(font
					(size 1.27 1.27)
				)
			)
		)
		(property "Value" ""
			(at 0 0 180)
			(layer "F.Fab")
			(effects
				(font
					(size 1.27 1.27)
				)
			)
		)
		(duplicate_pad_numbers_are_jumpers no)
		(fp_line
			(start 1.524 0.762)
			(end -1.524 0.762)
			(stroke
				(width 0.1524)
				(type default)
			)
			(layer "F.SilkS")
		)
		(fp_line
			(start 1.524 -0.762)
			(end 1.524 0.762)
			(stroke
				(width 0.1524)
				(type default)
			)
			(layer "F.SilkS")
		)
		(fp_line
			(start -1.524 0.762)
			(end -1.524 -0.762)
			(stroke
				(width 0.1524)
				(type default)
			)
			(layer "F.SilkS")
		)
		(fp_line
			(start -1.524 -0.762)
			(end 1.524 -0.762)
			(stroke
				(width 0.1524)
				(type default)
			)
			(layer "F.SilkS")
		)
		(fp_line
			(start 1.1049 0.724916)
			(end 1.1049 -0.724916)
			(stroke
				(width 0.1)
				(type default)
			)
			(layer "F.Fab")
		)
		(fp_line
			(start 1.1049 -0.724916)
			(end -1.1049 -0.724916)
			(stroke
				(width 0.1)
				(type default)
			)
			(layer "F.Fab")
		)
		(fp_line
			(start -1.1049 0.724916)
			(end 1.1049 0.724916)
			(stroke
				(width 0.1)
				(type default)
			)
			(layer "F.Fab")
		)
		(fp_line
			(start -1.1049 -0.724916)
			(end -1.1049 0.724916)
			(stroke
				(width 0.1)
				(type default)
			)
			(layer "F.Fab")
		)
		(pad "1" smd rect
			(at -0.889 0)
			(size 1.016 1.27)
			(layers "F.Cu" "F.Mask" "F.Paste")
			(net "PVCCIN_CPU1")
		)
		(pad "2" smd rect
			(at 0.889 0)
			(size 1.016 1.27)
			(layers "F.Cu" "F.Mask" "F.Paste")
			(net "GND")
		)
	)
	(footprint ""
		(layer "F.Cu")
		(at 123.317 -75.021948 90)
		(property "Reference" "R1184"
			(at 0 0 90)
			(layer "F.SilkS")
			(hide yes)
			(effects
				(font
					(size 1.27 1.27)
				)
			)
		)
		(property "Value" ""
			(at 0 0 90)
			(layer "F.Fab")
			(effects
				(font
					(size 1.27 1.27)
				)
			)
		)
		(duplicate_pad_numbers_are_jumpers no)
		(fp_line
			(start 0.7874 -0.4064)
			(end 0.7874 0.4064)
			(stroke
				(width 0.1524)
				(type default)
			)
			(layer "F.SilkS")
		)
		(fp_line
			(start -0.7874 -0.4064)
			(end 0.7874 -0.4064)
			(stroke
				(width 0.1524)
				(type default)
			)
			(layer "F.SilkS")
		)
		(fp_line
			(start 0.7874 0.4064)
			(end -0.7874 0.4064)
			(stroke
				(width 0.1524)
				(type default)
			)
			(layer "F.SilkS")
		)
		(fp_line
			(start -0.7874 0.4064)
			(end -0.7874 -0.4064)
			(stroke
				(width 0.1524)
				(type default)
			)
			(layer "F.SilkS")
		)
		(fp_line
			(start -0.12065 -0.305054)
			(end -0.12065 -0.2794)
			(stroke
				(width 0.1)
				(type default)
			)
			(layer "F.Fab")
		)
		(fp_line
			(start -0.67945 -0.305054)
			(end -0.12065 -0.305054)
			(stroke
				(width 0.1)
				(type default)
			)
			(layer "F.Fab")
		)
		(fp_line
			(start 0.67945 -0.3048)
			(end 0.67945 0.3048)
			(stroke
				(width 0.1)
				(type default)
			)
			(layer "F.Fab")
		)
		(fp_line
			(start 0.12065 -0.3048)
			(end 0.67945 -0.3048)
			(stroke
				(width 0.1)
				(type default)
			)
			(layer "F.Fab")
		)
		(fp_line
			(start 0.12065 -0.2794)
			(end 0.12065 -0.3048)
			(stroke
				(width 0.1)
				(type default)
			)
			(layer "F.Fab")
		)
		(fp_line
			(start -0.12065 -0.2794)
			(end 0.12065 -0.2794)
			(stroke
				(width 0.1)
				(type default)
			)
			(layer "F.Fab")
		)
		(fp_line
			(start 0.120396 0.2794)
			(end -0.12065 0.2794)
			(stroke
				(width 0.1)
				(type default)
			)
			(layer "F.Fab")
		)
		(fp_line
			(start -0.12065 0.2794)
			(end -0.12065 0.3048)
			(stroke
				(width 0.1)
				(type default)
			)
			(layer "F.Fab")
		)
		(fp_line
			(start 0.67945 0.3048)
			(end 0.120396 0.3048)
			(stroke
				(width 0.1)
				(type default)
			)
			(layer "F.Fab")
		)
		(fp_line
			(start 0.120396 0.3048)
			(end 0.120396 0.2794)
			(stroke
				(width 0.1)
				(type default)
			)
			(layer "F.Fab")
		)
		(fp_line
			(start -0.12065 0.3048)
			(end -0.67945 0.3048)
			(stroke
				(width 0.1)
				(type default)
			)
			(layer "F.Fab")
		)
		(fp_line
			(start -0.67945 0.3048)
			(end -0.67945 -0.305054)
			(stroke
				(width 0.1)
				(type default)
			)
			(layer "F.Fab")
		)
		(pad "1" smd circle
			(at -0.40005 0 90)
			(size 0 0)
			(layers "F.Cu" "F.Mask" "F.Paste")
			(net "JTAG_BMC_DBP_TMS_R")
		)
		(pad "2" smd circle
			(at 0.40005 0 90)
			(size 0 0)
			(layers "F.Cu" "F.Mask" "F.Paste")
			(net "JTAG_BMC_DBP_TMS")
		)
	)
)
